# S9S_MB_2U (Grand Teton) — schematic netlist excerpt (pin names and nets, part order shuffled) for the footprints in the layout excerpt that follows; sources: Cadence DE-HDL packaged netlist, KiCad conversion of 03242023_DA0F0TMBIJ0_F0T_Motherboard_J_brd_V01_OCP.brd

PC432  Q_CAP  22UF 16V 20% X6S  pkg C0805  page 294 : A = SW_P12V_PVCCINFAON_CPU1_FLT ; B = GND
PC401  Q_CAP  100NF 50V 10% X7R  pkg C0402  page 289 : A = SW_PVCCFA_EHV_FIVRA_CPU1_BOOT1_ ; B = SW_PVCCFA_EHV_FIVRA_CPU1_BOOTR1
R4494  Q_RES  10K 1% CHIP  pkg 0402LF  page 211 : A = FM_9ZXL045_3_OE_N ; B = P3V3

(kicad_pcb
	(version 20260206)
	(generator "pcbnew")
	(generator_version "10.0")
	(general
		(thickness 1.6)
		(legacy_teardrops no)
	)
	(paper "A4")
	(title_block
		(title "03242023_DA0F0TMBIJ0_F0T_Motherboard_J_brd_V01_OCP.brd")
		(comment 1 "Grand Teton / footprints 3659-3661 of 6105")
	)
	(layers
		(0 "F.Cu" signal "TOP")
		(4 "In1.Cu" signal "GND")
		(6 "In2.Cu" signal "IN1")
		(8 "In3.Cu" signal "GND1")
		(10 "In4.Cu" signal "IN2")
		(12 "In5.Cu" signal "GND2")
		(14 "In6.Cu" signal "IN3")
		(16 "In7.Cu" signal "GND3")
		(18 "In8.Cu" signal "VCC")
		(20 "In9.Cu" signal "VCC1")
		(22 "In10.Cu" signal "GND4")
		(24 "In11.Cu" signal "IN4")
		(26 "In12.Cu" signal "GND5")
		(28 "In13.Cu" signal "IN5")
		(30 "In14.Cu" signal "GND6")
		(32 "In15.Cu" signal "IN6")
		(34 "In16.Cu" signal "GND7")
		(2 "B.Cu" signal "BOTTOM")
		(9 "F.Adhes" user "F.Adhesive")
		(11 "B.Adhes" user "B.Adhesive")
		(13 "F.Paste" user "Package Geometry/Pastemask Top")
		(15 "B.Paste" user "Package Geometry/Pastemask Bottom")
		(5 "F.SilkS" user "Ref Des/Silkscreen Top")
		(7 "B.SilkS" user "Ref Des/Silkscreen Bottom")
		(1 "F.Mask" user "Board Geometry/Soldermask Top")
		(3 "B.Mask" user "Board Geometry/Soldermask Bottom")
		(17 "Dwgs.User" user "User.Drawings")
		(19 "Cmts.User" user "User.Comments")
		(21 "Eco1.User" user "User.Eco1")
		(23 "Eco2.User" user "User.Eco2")
		(25 "Edge.Cuts" user "Board Geometry/Outline")
		(27 "Margin" user)
		(31 "F.CrtYd" user "Package Geometry/Place Bound Top")
		(29 "B.CrtYd" user "Package Geometry/Place Bound Bottom")
		(35 "F.Fab" user "Ref Des/Assembly Top")
		(33 "B.Fab" user "Ref Des/Assembly Bottom")
	)
	(footprint ""
		(layer "F.Cu")
		(at 114.70132 -409.428442)
		(property "Reference" "R4494"
			(at 0 0 0)
			(layer "F.SilkS")
			(hide yes)
			(effects
				(font
					(size 1.27 1.27)
				)
			)
		)
		(property "Value" ""
			(at 0 0 0)
			(layer "F.Fab")
			(effects
				(font
					(size 1.27 1.27)
				)
			)
		)
		(duplicate_pad_numbers_are_jumpers no)
		(fp_line
			(start -0.7874 -0.4064)
			(end 0.7874 -0.4064)
			(stroke
				(width 0.1524)
				(type default)
			)
			(layer "F.SilkS")
		)
		(fp_line
			(start -0.7874 0.4064)
			(end -0.7874 -0.4064)
			(stroke
				(width 0.1524)
				(type default)
			)
			(layer "F.SilkS")
		)
		(fp_line
			(start 0.7874 -0.4064)
			(end 0.7874 0.4064)
			(stroke
				(width 0.1524)
				(type default)
			)
			(layer "F.SilkS")
		)
		(fp_line
			(start 0.7874 0.4064)
			(end -0.7874 0.4064)
			(stroke
				(width 0.1524)
				(type default)
			)
			(layer "F.SilkS")
		)
		(fp_line
			(start -0.67945 -0.305054)
			(end -0.12065 -0.305054)
			(stroke
				(width 0.1)
				(type default)
			)
			(layer "F.Fab")
		)
		(fp_line
			(start -0.67945 0.3048)
			(end -0.67945 -0.305054)
			(stroke
				(width 0.1)
				(type default)
			)
			(layer "F.Fab")
		)
		(fp_line
			(start -0.12065 -0.305054)
			(end -0.12065 -0.2794)
			(stroke
				(width 0.1)
				(type default)
			)
			(layer "F.Fab")
		)
		(fp_line
			(start -0.12065 -0.2794)
			(end 0.12065 -0.2794)
			(stroke
				(width 0.1)
				(type default)
			)
			(layer "F.Fab")
		)
		(fp_line
			(start -0.12065 0.2794)
			(end -0.12065 0.3048)
			(stroke
				(width 0.1)
				(type default)
			)
			(layer "F.Fab")
		)
		(fp_line
			(start -0.12065 0.3048)
			(end -0.67945 0.3048)
			(stroke
				(width 0.1)
				(type default)
			)
			(layer "F.Fab")
		)
		(fp_line
			(start 0.120396 0.2794)
			(end -0.12065 0.2794)
			(stroke
				(width 0.1)
				(type default)
			)
			(layer "F.Fab")
		)
		(fp_line
			(start 0.120396 0.3048)
			(end 0.120396 0.2794)
			(stroke
				(width 0.1)
				(type default)
			)
			(layer "F.Fab")
		)
		(fp_line
			(start 0.12065 -0.3048)
			(end 0.67945 -0.3048)
			(stroke
				(width 0.1)
				(type default)
			)
			(layer "F.Fab")
		)
		(fp_line
			(start 0.12065 -0.2794)
			(end 0.12065 -0.3048)
			(stroke
				(width 0.1)
				(type default)
			)
			(layer "F.Fab")
		)
		(fp_line
			(start 0.67945 -0.3048)
			(end 0.67945 0.3048)
			(stroke
				(width 0.1)
				(type default)
			)
			(layer "F.Fab")
		)
		(fp_line
			(start 0.67945 0.3048)
			(end 0.120396 0.3048)
			(stroke
				(width 0.1)
				(type default)
			)
			(layer "F.Fab")
		)
		(pad "1" smd circle
			(at -0.40005 0)
			(size 0 0)
			(layers "F.Cu" "F.Mask" "F.Paste")
			(net "FM_9ZXL045_3_OE_N")
		)
		(pad "2" smd circle
			(at 0.40005 0)
			(size 0 0)
			(layers "F.Cu" "F.Mask" "F.Paste")
			(net "P3V3")
		)
	)
	(footprint ""
		(layer "F.Cu")
		(at 47.159418 -178.060604 90)
		(property "Reference" "PC432"
			(at 0 0 90)
			(layer "F.SilkS")
			(hide yes)
			(effects
				(font
					(size 1.27 1.27)
				)
			)
		)
		(property "Value" ""
			(at 0 0 90)
			(layer "F.Fab")
			(effects
				(font
					(size 1.27 1.27)
				)
			)
		)
		(duplicate_pad_numbers_are_jumpers no)
		(fp_line
			(start 1.524 -0.762)
			(end 1.524 0.762)
			(stroke
				(width 0.1524)
				(type default)
			)
			(layer "F.SilkS")
		)
		(fp_line
			(start -1.524 -0.762)
			(end 1.524 -0.762)
			(stroke
				(width 0.1524)
				(type default)
			)
			(layer "F.SilkS")
		)
		(fp_line
			(start 1.524 0.762)
			(end -1.524 0.762)
			(stroke
				(width 0.1524)
				(type default)
			)
			(layer "F.SilkS")
		)
		(fp_line
			(start -1.524 0.762)
			(end -1.524 -0.762)
			(stroke
				(width 0.1524)
				(type default)
			)
			(layer "F.SilkS")
		)
		(fp_line
			(start 1.1049 -0.724916)
			(end -1.1049 -0.724916)
			(stroke
				(width 0.1)
				(type default)
			)
			(layer "F.Fab")
		)
		(fp_line
			(start -1.1049 -0.724916)
			(end -1.1049 0.724916)
			(stroke
				(width 0.1)
				(type default)
			)
			(layer "F.Fab")
		)
		(fp_line
			(start 1.1049 0.724916)
			(end 1.1049 -0.724916)
			(stroke
				(width 0.1)
				(type default)
			)
			(layer "F.Fab")
		)
		(fp_line
			(start -1.1049 0.724916)
			(end 1.1049 0.724916)
			(stroke
				(width 0.1)
				(type default)
			)
			(layer "F.Fab")
		)
		(pad "1" smd rect
			(at -0.889 0 270)
			(size 1.016 1.27)
			(layers "F.Cu" "F.Mask" "F.Paste")
			(net "SW_P12V_PVCCINFAON_CPU1_FLT")
		)
		(pad "2" smd rect
			(at 0.889 0 270)
			(size 1.016 1.27)
			(layers "F.Cu" "F.Mask" "F.Paste")
			(net "GND")
		)
	)
	(footprint ""
		(layer "F.Cu")
		(at 173.810168 -358.15778 -90)
		(property "Reference" "PC401"
			(at 0 0 270)
			(layer "F.SilkS")
			(hide yes)
			(effects
				(font
					(size 1.27 1.27)
				)
			)
		)
		(property "Value" ""
			(at 0 0 270)
			(layer "F.Fab")
			(effects
				(font
					(size 1.27 1.27)
				)
			)
		)
		(duplicate_pad_numbers_are_jumpers no)
		(fp_line
			(start -0.7874 0.4064)
			(end -0.7874 -0.4064)
			(stroke
				(width 0.1524)
				(type default)
			)
			(layer "F.SilkS")
		)
		(fp_line
			(start 0.7874 0.4064)
			(end -0.7874 0.4064)
			(stroke
				(width 0.1524)
				(type default)
			)
			(layer "F.SilkS")
		)
		(fp_line
			(start -0.7874 -0.4064)
			(end 0.7874 -0.4064)
			(stroke
				(width 0.1524)
				(type default)
			)
			(layer "F.SilkS")
		)
		(fp_line
			(start 0.7874 -0.4064)
			(end 0.7874 0.4064)
			(stroke
				(width 0.1524)
				(type default)
			)
			(layer "F.SilkS")
		)
		(fp_line
			(start -0.67945 0.3048)
			(end -0.67945 -0.305054)
			(stroke
				(width 0.1)
				(type default)
			)
			(layer "F.Fab")
		)
		(fp_line
			(start -0.12065 0.3048)
			(end -0.67945 0.3048)
			(stroke
				(width 0.1)
				(type default)
			)
			(layer "F.Fab")
		)
		(fp_line
			(start 0.120396 0.3048)
			(end 0.120396 0.2794)
			(stroke
				(width 0.1)
				(type default)
			)
			(layer "F.Fab")
		)
		(fp_line
			(start 0.67945 0.3048)
			(end 0.120396 0.3048)
			(stroke
				(width 0.1)
				(type default)
			)
			(layer "F.Fab")
		)
		(fp_line
			(start -0.12065 0.2794)
			(end -0.12065 0.3048)
			(stroke
				(width 0.1)
				(type default)
			)
			(layer "F.Fab")
		)
		(fp_line
			(start 0.120396 0.2794)
			(end -0.12065 0.2794)
			(stroke
				(width 0.1)
				(type default)
			)
			(layer "F.Fab")
		)
		(fp_line
			(start -0.12065 -0.2794)
			(end 0.12065 -0.2794)
			(stroke
				(width 0.1)
				(type default)
			)
			(layer "F.Fab")
		)
		(fp_line
			(start 0.12065 -0.2794)
			(end 0.12065 -0.3048)
			(stroke
				(width 0.1)
				(type default)
			)
			(layer "F.Fab")
		)
		(fp_line
			(start 0.12065 -0.3048)
			(end 0.67945 -0.3048)
			(stroke
				(width 0.1)
				(type default)
			)
			(layer "F.Fab")
		)
		(fp_line
			(start 0.67945 -0.3048)
			(end 0.67945 0.3048)
			(stroke
				(width 0.1)
				(type default)
			)
			(layer "F.Fab")
		)
		(fp_line
			(start -0.67945 -0.305054)
			(end -0.12065 -0.305054)
			(stroke
				(width 0.1)
				(type default)
			)
			(layer "F.Fab")
		)
		(fp_line
			(start -0.12065 -0.305054)
			(end -0.12065 -0.2794)
			(stroke
				(width 0.1)
				(type default)
			)
			(layer "F.Fab")
		)
		(pad "1" smd circle
			(at -0.40005 0 270)
			(size 0 0)
			(layers "F.Cu" "F.Mask" "F.Paste")
			(net "SW_PVCCFA_EHV_FIVRA_CPU1_BOOT1_")
		)
		(pad "2" smd circle
			(at 0.40005 0 270)
			(size 0 0)
			(layers "F.Cu" "F.Mask" "F.Paste")
			(net "SW_PVCCFA_EHV_FIVRA_CPU1_BOOTR1")
		)
	)
)
